(kicad_pcb
	(version 20260206)
	(generator "pcbnew")
	(generator_version "10.0")
	(general
		(thickness 1.6)
		(legacy_teardrops no)
	)
	(paper "A4")
	(title_block
		(title "Bryce Canyon_F.DPB_16315-1-OCP.brd")
		(comment 1 "Bryce Canyon / footprint 407 of 2223 (MONO2), pads 148-166 of 166")
	)
	(layers
		(0 "F.Cu" signal "TOP")
		(4 "In1.Cu" signal "L2GND")
		(6 "In2.Cu" signal "L3")
		(8 "In3.Cu" signal "L4GND")
		(10 "In4.Cu" signal "L5")
		(12 "In5.Cu" signal "L6VCC")
		(14 "In6.Cu" signal "L7VCC")
		(16 "In7.Cu" signal "L8")
		(18 "In8.Cu" signal "L9GND")
		(20 "In9.Cu" signal "L10")
		(22 "In10.Cu" signal "L11GND")
		(2 "B.Cu" signal "BOTTOM")
		(9 "F.Adhes" user "F.Adhesive")
		(11 "B.Adhes" user "B.Adhesive")
		(13 "F.Paste" user "Package Geometry/Pastemask Top")
		(15 "B.Paste" user "Package Geometry/Pastemask Bottom")
		(5 "F.SilkS" user "Ref Des/Silkscreen Top")
		(7 "B.SilkS" user "Ref Des/Silkscreen Bottom")
		(1 "F.Mask" user "Board Geometry/Soldermask Top")
		(3 "B.Mask" user "Board Geometry/Soldermask Bottom")
		(17 "Dwgs.User" user "User.Drawings")
		(19 "Cmts.User" user "User.Comments")
		(21 "Eco1.User" user "User.Eco1")
		(23 "Eco2.User" user "User.Eco2")
		(25 "Edge.Cuts" user "Board Geometry/Outline")
		(27 "Margin" user)
		(31 "F.CrtYd" user "Package Geometry/Place Bound Top")
		(29 "B.CrtYd" user "Package Geometry/Place Bound Bottom")
		(35 "F.Fab" user "Ref Des/Assembly Top")
		(33 "B.Fab" user "Ref Des/Assembly Bottom")
	)
	(footprint ""
		(layer "F.Cu")
		(at 239.300004 -14.85011 90)
		(property "Reference" "MONO2"
			(at 0 0 90)
			(layer "F.SilkS")
			(hide yes)
			(effects
				(font
					(size 1.27 1.27)
				)
			)
		)
		(property "Value" "AMP-CONN164-4R-1-GP"
			(at -25.705054 -1.203706 90)
			(unlocked yes)
			(layer "F.Fab")
			(hide yes)
			(effects
				(font
					(size 1.016 1.016)
					(thickness 0.1524)
				)
			)
		)
		(property "Device Type" "PREFIT-164P-890091-1H441"
			(at -25.705054 -2.727706 90)
			(unlocked yes)
			(layer "F.Fab")
			(hide yes)
			(effects
				(font
					(size 1.016 1.016)
					(thickness 0.1524)
				)
			)
		)
		(duplicate_pad_numbers_are_jumpers no)
		(pad "B64" thru_hole circle
			(at 53.349906 3.24993 90)
			(size 1.0668 1.0668)
			(drill 0.719836)
			(layers "*.Cu" "*.Mask")
			(remove_unused_layers no)
			(net "PCIE_COMP_A_TO_IOM_A_19_DN")
			(clearance 0.1905)
			(thermal_gap 0.1905)
		)
		(pad "B65" thru_hole circle
			(at 54.349904 1.249934 90)
			(size 1.0668 1.0668)
			(drill 0.719836)
			(layers "*.Cu" "*.Mask")
			(remove_unused_layers no)
			(net "GND")
			(clearance 0.1905)
			(thermal_gap 0.1905)
		)
		(pad "B66" thru_hole circle
			(at 55.349902 3.24993 90)
			(size 1.0668 1.0668)
			(drill 0.719836)
			(layers "*.Cu" "*.Mask")
			(remove_unused_layers no)
			(net "GND")
			(clearance 0.1905)
			(thermal_gap 0.1905)
		)
		(pad "B67" thru_hole circle
			(at 56.3499 1.249934 90)
			(size 1.0668 1.0668)
			(drill 0.719836)
			(layers "*.Cu" "*.Mask")
			(remove_unused_layers no)
			(net "PCIE_COMP_A_TO_IOM_A_20_DP")
			(clearance 0.1905)
			(thermal_gap 0.1905)
		)
		(pad "B68" thru_hole circle
			(at 57.349898 3.24993 90)
			(size 1.0668 1.0668)
			(drill 0.719836)
			(layers "*.Cu" "*.Mask")
			(remove_unused_layers no)
			(net "PCIE_COMP_A_TO_IOM_A_20_DN")
			(clearance 0.1905)
			(thermal_gap 0.1905)
		)
		(pad "B69" thru_hole circle
			(at 58.349896 1.249934 90)
			(size 1.0668 1.0668)
			(drill 0.719836)
			(layers "*.Cu" "*.Mask")
			(remove_unused_layers no)
			(net "GND")
			(clearance 0.1905)
			(thermal_gap 0.1905)
		)
		(pad "B70" thru_hole circle
			(at 59.349894 3.24993 90)
			(size 1.0668 1.0668)
			(drill 0.719836)
			(layers "*.Cu" "*.Mask")
			(remove_unused_layers no)
			(net "GND")
			(clearance 0.1905)
			(thermal_gap 0.1905)
		)
		(pad "B71" thru_hole circle
			(at 60.349892 1.249934 90)
			(size 1.0668 1.0668)
			(drill 0.719836)
			(layers "*.Cu" "*.Mask")
			(remove_unused_layers no)
			(net "PCIE_COMP_A_TO_IOM_A_21_DP")
			(clearance 0.1905)
			(thermal_gap 0.1905)
		)
		(pad "B72" thru_hole circle
			(at 61.34989 3.24993 90)
			(size 1.0668 1.0668)
			(drill 0.719836)
			(layers "*.Cu" "*.Mask")
			(remove_unused_layers no)
			(net "PCIE_COMP_A_TO_IOM_A_21_DN")
			(clearance 0.1905)
			(thermal_gap 0.1905)
		)
		(pad "B73" thru_hole circle
			(at 62.349888 1.249934 90)
			(size 1.0668 1.0668)
			(drill 0.719836)
			(layers "*.Cu" "*.Mask")
			(remove_unused_layers no)
			(net "GND")
			(clearance 0.1905)
			(thermal_gap 0.1905)
		)
		(pad "B74" thru_hole circle
			(at 63.349886 3.24993 90)
			(size 1.0668 1.0668)
			(drill 0.719836)
			(layers "*.Cu" "*.Mask")
			(remove_unused_layers no)
			(net "GND")
			(clearance 0.1905)
			(thermal_gap 0.1905)
		)
		(pad "B75" thru_hole circle
			(at 64.349884 1.249934 90)
			(size 1.0668 1.0668)
			(drill 0.719836)
			(layers "*.Cu" "*.Mask")
			(remove_unused_layers no)
			(net "PCIE_COMP_A_TO_IOM_A_22_DP")
			(clearance 0.1905)
			(thermal_gap 0.1905)
		)
		(pad "B76" thru_hole circle
			(at 65.349882 3.24993 90)
			(size 1.0668 1.0668)
			(drill 0.719836)
			(layers "*.Cu" "*.Mask")
			(remove_unused_layers no)
			(net "PCIE_COMP_A_TO_IOM_A_22_DN")
			(clearance 0.1905)
			(thermal_gap 0.1905)
		)
		(pad "B77" thru_hole circle
			(at 66.34988 1.249934 90)
			(size 1.0668 1.0668)
			(drill 0.719836)
			(layers "*.Cu" "*.Mask")
			(remove_unused_layers no)
			(net "GND")
			(clearance 0.1905)
			(thermal_gap 0.1905)
		)
		(pad "B78" thru_hole circle
			(at 67.349878 3.24993 90)
			(size 1.0668 1.0668)
			(drill 0.719836)
			(layers "*.Cu" "*.Mask")
			(remove_unused_layers no)
			(net "GND")
			(clearance 0.1905)
			(thermal_gap 0.1905)
		)
		(pad "B79" thru_hole circle
			(at 68.349876 1.249934 90)
			(size 1.0668 1.0668)
			(drill 0.719836)
			(layers "*.Cu" "*.Mask")
			(remove_unused_layers no)
			(net "PCIE_COMP_A_TO_IOM_A_23_DP")
			(clearance 0.1905)
			(thermal_gap 0.1905)
		)
		(pad "B80" thru_hole circle
			(at 69.349874 3.24993 90)
			(size 1.0668 1.0668)
			(drill 0.719836)
			(layers "*.Cu" "*.Mask")
			(remove_unused_layers no)
			(net "PCIE_COMP_A_TO_IOM_A_23_DN")
			(clearance 0.1905)
			(thermal_gap 0.1905)
		)
		(pad "B81" thru_hole circle
			(at 70.350126 1.249934 90)
			(size 1.0668 1.0668)
			(drill 0.719836)
			(layers "*.Cu" "*.Mask")
			(remove_unused_layers no)
			(net "GND")
			(clearance 0.1905)
			(thermal_gap 0.1905)
		)
		(pad "B82" thru_hole circle
			(at 71.350124 3.24993 90)
			(size 1.0668 1.0668)
			(drill 0.719836)
			(layers "*.Cu" "*.Mask")
			(remove_unused_layers no)
			(net "COMP_A_POWER_FAIL_N")
			(clearance 0.1905)
			(thermal_gap 0.1905)
		)
	)
)
